# T6G (Grand Teton) — schematic netlist excerpt (pin names and nets, part order shuffled) for the footprints in the layout excerpt that follows; sources: Cadence DE-HDL packaged netlist, KiCad conversion of 04192023_DAF0TMB3IC0_F0TG_MB_C_brd_V02_OCP.brd

R1329  Q_RES  0 5% CHIP  pkg 0402LF  page 82 : A = E1S_0_P3V3_P12V_ADC_R_ALERT ; B = E1S_0_P3V3_P12V_ADC_ALERT
C5000  Q_CAP  1000PF 50V 5% X7R  pkg 0402  page 34 : A = FM_BIOS_POST_CMPLT_BUF_N ; B = GND

(kicad_pcb
	(version 20260206)
	(generator "pcbnew")
	(generator_version "10.0")
	(general
		(thickness 1.6)
		(legacy_teardrops no)
	)
	(paper "A4")
	(title_block
		(title "04192023_DAF0TMB3IC0_F0TG_MB_C_brd_V02_OCP.brd")
		(comment 1 "Grand Teton / footprints 8074-8075 of 8354")
	)
	(layers
		(0 "F.Cu" signal "TOP")
		(4 "In1.Cu" signal "GND")
		(6 "In2.Cu" signal "IN1")
		(8 "In3.Cu" signal "GND1")
		(10 "In4.Cu" signal "IN2")
		(12 "In5.Cu" signal "GND2")
		(14 "In6.Cu" signal "IN3")
		(16 "In7.Cu" signal "GND3")
		(18 "In8.Cu" signal "VCC")
		(20 "In9.Cu" signal "VCC1")
		(22 "In10.Cu" signal "GND4")
		(24 "In11.Cu" signal "IN4")
		(26 "In12.Cu" signal "GND5")
		(28 "In13.Cu" signal "IN5")
		(30 "In14.Cu" signal "GND6")
		(32 "In15.Cu" signal "IN6")
		(34 "In16.Cu" signal "GND7")
		(2 "B.Cu" signal "BOTTOM")
		(9 "F.Adhes" user "F.Adhesive")
		(11 "B.Adhes" user "B.Adhesive")
		(13 "F.Paste" user "Package Geometry/Pastemask Top")
		(15 "B.Paste" user "Package Geometry/Pastemask Bottom")
		(5 "F.SilkS" user "Ref Des/Silkscreen Top")
		(7 "B.SilkS" user "Ref Des/Silkscreen Bottom")
		(1 "F.Mask" user "Board Geometry/Soldermask Top")
		(3 "B.Mask" user "Board Geometry/Soldermask Bottom")
		(17 "Dwgs.User" user "User.Drawings")
		(19 "Cmts.User" user "User.Comments")
		(21 "Eco1.User" user "User.Eco1")
		(23 "Eco2.User" user "User.Eco2")
		(25 "Edge.Cuts" user "Board Geometry/Outline")
		(27 "Margin" user)
		(31 "F.CrtYd" user "Package Geometry/Place Bound Top")
		(29 "B.CrtYd" user "Package Geometry/Place Bound Bottom")
		(35 "F.Fab" user "Ref Des/Assembly Top")
		(33 "B.Fab" user "Ref Des/Assembly Bottom")
	)
	(footprint ""
		(layer "B.Cu")
		(at 399.518124 -344.850212 90)
		(property "Reference" "C5000"
			(at 0 0 90)
			(layer "B.SilkS")
			(hide yes)
			(effects
				(font
					(size 1.27 1.27)
				)
				(justify mirror)
			)
		)
		(property "Value" ""
			(at 0 0 90)
			(layer "B.Fab")
			(effects
				(font
					(size 1.27 1.27)
				)
				(justify mirror)
			)
		)
		(duplicate_pad_numbers_are_jumpers no)
		(fp_line
			(start 0.7874 -0.4064)
			(end -0.7874 -0.4064)
			(stroke
				(width 0.1524)
				(type default)
			)
			(layer "B.SilkS")
		)
		(fp_line
			(start -0.7874 -0.4064)
			(end -0.7874 0.4064)
			(stroke
				(width 0.1524)
				(type default)
			)
			(layer "B.SilkS")
		)
		(fp_line
			(start 0.7874 0.4064)
			(end 0.7874 -0.4064)
			(stroke
				(width 0.1524)
				(type default)
			)
			(layer "B.SilkS")
		)
		(fp_line
			(start -0.7874 0.4064)
			(end 0.7874 0.4064)
			(stroke
				(width 0.1524)
				(type default)
			)
			(layer "B.SilkS")
		)
		(fp_line
			(start 0.67945 -0.305054)
			(end 0.12065 -0.305054)
			(stroke
				(width 0.1)
				(type default)
			)
			(layer "B.Fab")
		)
		(fp_line
			(start 0.12065 -0.305054)
			(end 0.12065 -0.2794)
			(stroke
				(width 0.1)
				(type default)
			)
			(layer "B.Fab")
		)
		(fp_line
			(start -0.12065 -0.3048)
			(end -0.67945 -0.3048)
			(stroke
				(width 0.1)
				(type default)
			)
			(layer "B.Fab")
		)
		(fp_line
			(start -0.67945 -0.3048)
			(end -0.67945 0.3048)
			(stroke
				(width 0.1)
				(type default)
			)
			(layer "B.Fab")
		)
		(fp_line
			(start 0.12065 -0.2794)
			(end -0.12065 -0.2794)
			(stroke
				(width 0.1)
				(type default)
			)
			(layer "B.Fab")
		)
		(fp_line
			(start -0.12065 -0.2794)
			(end -0.12065 -0.3048)
			(stroke
				(width 0.1)
				(type default)
			)
			(layer "B.Fab")
		)
		(fp_line
			(start 0.12065 0.2794)
			(end 0.12065 0.3048)
			(stroke
				(width 0.1)
				(type default)
			)
			(layer "B.Fab")
		)
		(fp_line
			(start -0.120396 0.2794)
			(end 0.12065 0.2794)
			(stroke
				(width 0.1)
				(type default)
			)
			(layer "B.Fab")
		)
		(fp_line
			(start 0.67945 0.3048)
			(end 0.67945 -0.305054)
			(stroke
				(width 0.1)
				(type default)
			)
			(layer "B.Fab")
		)
		(fp_line
			(start 0.12065 0.3048)
			(end 0.67945 0.3048)
			(stroke
				(width 0.1)
				(type default)
			)
			(layer "B.Fab")
		)
		(fp_line
			(start -0.120396 0.3048)
			(end -0.120396 0.2794)
			(stroke
				(width 0.1)
				(type default)
			)
			(layer "B.Fab")
		)
		(fp_line
			(start -0.67945 0.3048)
			(end -0.120396 0.3048)
			(stroke
				(width 0.1)
				(type default)
			)
			(layer "B.Fab")
		)
		(pad "1" smd circle
			(at 0.40005 0 270)
			(size 0 0)
			(layers "B.Cu" "B.Mask" "B.Paste")
			(net "FM_BIOS_POST_CMPLT_BUF_N")
		)
		(pad "2" smd circle
			(at -0.40005 0 270)
			(size 0 0)
			(layers "B.Cu" "B.Mask" "B.Paste")
			(net "GND")
		)
	)
	(footprint ""
		(layer "B.Cu")
		(at 177.673 -100.294948 -90)
		(property "Reference" "R1329"
			(at 0 0 90)
			(layer "B.SilkS")
			(hide yes)
			(effects
				(font
					(size 1.27 1.27)
				)
				(justify mirror)
			)
		)
		(property "Value" ""
			(at 0 0 90)
			(layer "B.Fab")
			(effects
				(font
					(size 1.27 1.27)
				)
				(justify mirror)
			)
		)
		(duplicate_pad_numbers_are_jumpers no)
		(fp_line
			(start -0.7874 0.4064)
			(end 0.7874 0.4064)
			(stroke
				(width 0.1524)
				(type default)
			)
			(layer "B.SilkS")
		)
		(fp_line
			(start 0.7874 0.4064)
			(end 0.7874 -0.4064)
			(stroke
				(width 0.1524)
				(type default)
			)
			(layer "B.SilkS")
		)
		(fp_line
			(start -0.7874 -0.4064)
			(end -0.7874 0.4064)
			(stroke
				(width 0.1524)
				(type default)
			)
			(layer "B.SilkS")
		)
		(fp_line
			(start 0.7874 -0.4064)
			(end -0.7874 -0.4064)
			(stroke
				(width 0.1524)
				(type default)
			)
			(layer "B.SilkS")
		)
		(fp_line
			(start -0.67945 0.3048)
			(end -0.120396 0.3048)
			(stroke
				(width 0.1)
				(type default)
			)
			(layer "B.Fab")
		)
		(fp_line
			(start -0.120396 0.3048)
			(end -0.120396 0.2794)
			(stroke
				(width 0.1)
				(type default)
			)
			(layer "B.Fab")
		)
		(fp_line
			(start 0.12065 0.3048)
			(end 0.67945 0.3048)
			(stroke
				(width 0.1)
				(type default)
			)
			(layer "B.Fab")
		)
		(fp_line
			(start 0.67945 0.3048)
			(end 0.67945 -0.305054)
			(stroke
				(width 0.1)
				(type default)
			)
			(layer "B.Fab")
		)
		(fp_line
			(start -0.120396 0.2794)
			(end 0.12065 0.2794)
			(stroke
				(width 0.1)
				(type default)
			)
			(layer "B.Fab")
		)
		(fp_line
			(start 0.12065 0.2794)
			(end 0.12065 0.3048)
			(stroke
				(width 0.1)
				(type default)
			)
			(layer "B.Fab")
		)
		(fp_line
			(start -0.12065 -0.2794)
			(end -0.12065 -0.3048)
			(stroke
				(width 0.1)
				(type default)
			)
			(layer "B.Fab")
		)
		(fp_line
			(start 0.12065 -0.2794)
			(end -0.12065 -0.2794)
			(stroke
				(width 0.1)
				(type default)
			)
			(layer "B.Fab")
		)
		(fp_line
			(start -0.67945 -0.3048)
			(end -0.67945 0.3048)
			(stroke
				(width 0.1)
				(type default)
			)
			(layer "B.Fab")
		)
		(fp_line
			(start -0.12065 -0.3048)
			(end -0.67945 -0.3048)
			(stroke
				(width 0.1)
				(type default)
			)
			(layer "B.Fab")
		)
		(fp_line
			(start 0.12065 -0.305054)
			(end 0.12065 -0.2794)
			(stroke
				(width 0.1)
				(type default)
			)
			(layer "B.Fab")
		)
		(fp_line
			(start 0.67945 -0.305054)
			(end 0.12065 -0.305054)
			(stroke
				(width 0.1)
				(type default)
			)
			(layer "B.Fab")
		)
		(pad "1" smd circle
			(at 0.40005 0 90)
			(size 0 0)
			(layers "B.Cu" "B.Mask" "B.Paste")
			(net "E1S_0_P3V3_P12V_ADC_R_ALERT")
		)
		(pad "2" smd circle
			(at -0.40005 0 90)
			(size 0 0)
			(layers "B.Cu" "B.Mask" "B.Paste")
			(net "E1S_0_P3V3_P12V_ADC_ALERT")
		)
	)
)
